(kicad_pcb
	(version 20260206)
	(generator "pcbnew")
	(generator_version "10.0")
	(general
		(thickness 1.6)
		(legacy_teardrops no)
	)
	(paper "A4")
	(title_block
		(title "01162023_DA0F0TEBIF0_F0T_Expander_BD_F_brd_V02_OCP.brd")
		(comment 1 "Grand Teton / footprints 199-204 of 9728")
	)
	(layers
		(0 "F.Cu" signal "TOP")
		(4 "In1.Cu" signal "GND")
		(6 "In2.Cu" signal "VCC")
		(8 "In3.Cu" signal "VCC1")
		(10 "In4.Cu" signal "GND1")
		(12 "In5.Cu" signal "IN1")
		(14 "In6.Cu" signal "GND2")
		(16 "In7.Cu" signal "IN2")
		(18 "In8.Cu" signal "GND3")
		(20 "In9.Cu" signal "IN3")
		(22 "In10.Cu" signal "GND4")
		(24 "In11.Cu" signal "IN4")
		(26 "In12.Cu" signal "GND5")
		(28 "In13.Cu" signal "IN5")
		(30 "In14.Cu" signal "GND6")
		(32 "In15.Cu" signal "IN6")
		(34 "In16.Cu" signal "GND7")
		(2 "B.Cu" signal "BOTTOM")
		(9 "F.Adhes" user "F.Adhesive")
		(11 "B.Adhes" user "B.Adhesive")
		(13 "F.Paste" user "Package Geometry/Pastemask Top")
		(15 "B.Paste" user "Package Geometry/Pastemask Bottom")
		(5 "F.SilkS" user "Ref Des/Silkscreen Top")
		(7 "B.SilkS" user "Ref Des/Silkscreen Bottom")
		(1 "F.Mask" user "Board Geometry/Soldermask Top")
		(3 "B.Mask" user "Board Geometry/Soldermask Bottom")
		(17 "Dwgs.User" user "User.Drawings")
		(19 "Cmts.User" user "User.Comments")
		(21 "Eco1.User" user "User.Eco1")
		(23 "Eco2.User" user "User.Eco2")
		(25 "Edge.Cuts" user "Board Geometry/Outline")
		(27 "Margin" user)
		(31 "F.CrtYd" user "Package Geometry/Place Bound Top")
		(29 "B.CrtYd" user "Package Geometry/Place Bound Bottom")
		(35 "F.Fab" user "Ref Des/Assembly Top")
		(33 "B.Fab" user "Ref Des/Assembly Bottom")
	)
	(footprint ""
		(layer "F.Cu")
		(at 337.488022 -319.545462 90)
		(property "Reference" "L63"
			(at 0 0 90)
			(layer "F.SilkS")
			(hide yes)
			(effects
				(font
					(size 1.27 1.27)
				)
			)
		)
		(property "Value" ""
			(at 0 0 90)
			(layer "F.Fab")
			(effects
				(font
					(size 1.27 1.27)
				)
			)
		)
		(duplicate_pad_numbers_are_jumpers no)
		(fp_line
			(start 2.248154 -4.9911)
			(end -2.248154 -4.9911)
			(stroke
				(width 0.1524)
				(type default)
			)
			(layer "F.SilkS")
		)
		(fp_line
			(start -2.248154 -4.9911)
			(end -2.248154 -1.618234)
			(stroke
				(width 0.1524)
				(type default)
			)
			(layer "F.SilkS")
		)
		(fp_line
			(start 2.248154 -1.7018)
			(end 2.248154 -4.9911)
			(stroke
				(width 0.1524)
				(type default)
			)
			(layer "F.SilkS")
		)
		(fp_line
			(start -2.248154 1.708658)
			(end -2.248154 4.9911)
			(stroke
				(width 0.1524)
				(type default)
			)
			(layer "F.SilkS")
		)
		(fp_line
			(start 2.248154 4.9911)
			(end 2.248154 1.679956)
			(stroke
				(width 0.1524)
				(type default)
			)
			(layer "F.SilkS")
		)
		(fp_line
			(start -2.248154 4.9911)
			(end 2.248154 4.9911)
			(stroke
				(width 0.1524)
				(type default)
			)
			(layer "F.SilkS")
		)
		(fp_line
			(start 1.700022 -0.899922)
			(end -1.700022 -0.899922)
			(stroke
				(width 0.1)
				(type default)
			)
			(layer "F.Fab")
		)
		(fp_line
			(start -1.700022 -0.899922)
			(end -1.700022 0.899922)
			(stroke
				(width 0.1)
				(type default)
			)
			(layer "F.Fab")
		)
		(fp_line
			(start 1.700022 0.899922)
			(end 1.700022 -0.899922)
			(stroke
				(width 0.1)
				(type default)
			)
			(layer "F.Fab")
		)
		(fp_line
			(start -1.700022 0.899922)
			(end 1.700022 0.899922)
			(stroke
				(width 0.1)
				(type default)
			)
			(layer "F.Fab")
		)
		(pad "1" smd rect
			(at -1.575054 0 90)
			(size 1.1684 9.8044)
			(layers "F.Cu" "F.Mask" "F.Paste")
			(net "P0V8_PEX2")
		)
		(pad "2" smd rect
			(at 1.575054 0 90)
			(size 1.1684 9.8044)
			(layers "F.Cu" "F.Mask" "F.Paste")
			(net "P0V8_SERDES_VDDA_PEX2")
		)
	)
	(footprint ""
		(layer "F.Cu")
		(at 142.926308 -343.952322 90)
		(property "Reference" "C2245"
			(at 0 0 90)
			(layer "F.SilkS")
			(hide yes)
			(effects
				(font
					(size 1.27 1.27)
				)
			)
		)
		(property "Value" ""
			(at 0 0 90)
			(layer "F.Fab")
			(effects
				(font
					(size 1.27 1.27)
				)
			)
		)
		(duplicate_pad_numbers_are_jumpers no)
		(fp_line
			(start 0.299974 -0.150114)
			(end 0.299974 0.150114)
			(stroke
				(width 0.1)
				(type default)
			)
			(layer "F.Fab")
		)
		(fp_line
			(start -0.299974 -0.150114)
			(end 0.299974 -0.150114)
			(stroke
				(width 0.1)
				(type default)
			)
			(layer "F.Fab")
		)
		(fp_line
			(start 0.299974 0.150114)
			(end -0.299974 0.150114)
			(stroke
				(width 0.1)
				(type default)
			)
			(layer "F.Fab")
		)
		(fp_line
			(start -0.299974 0.150114)
			(end -0.299974 -0.150114)
			(stroke
				(width 0.1)
				(type default)
			)
			(layer "F.Fab")
		)
		(pad "1" smd rect
			(at -0.2667 0 90)
			(size 0.3048 0.381)
			(layers "F.Cu" "F.Mask" "F.Paste")
			(net "P5E_PEX1_STN5_TX_DP<94>")
		)
		(pad "2" smd rect
			(at 0.2667 0 90)
			(size 0.3048 0.381)
			(layers "F.Cu" "F.Mask" "F.Paste")
			(net "P5E_PEX1_STN5_TX_C_DP<94>")
		)
	)
	(footprint ""
		(layer "F.Cu")
		(at 101.780594 -308.531768 -90)
		(property "Reference" "C4196"
			(at 0 0 270)
			(layer "F.SilkS")
			(hide yes)
			(effects
				(font
					(size 1.27 1.27)
				)
			)
		)
		(property "Value" ""
			(at 0 0 270)
			(layer "F.Fab")
			(effects
				(font
					(size 1.27 1.27)
				)
			)
		)
		(duplicate_pad_numbers_are_jumpers no)
		(fp_line
			(start -1.2954 0.5842)
			(end -1.2954 -0.5842)
			(stroke
				(width 0.1524)
				(type default)
			)
			(layer "F.SilkS")
		)
		(fp_line
			(start 1.2954 0.5842)
			(end -1.2954 0.5842)
			(stroke
				(width 0.1524)
				(type default)
			)
			(layer "F.SilkS")
		)
		(fp_line
			(start -1.2954 -0.5842)
			(end 1.2954 -0.5842)
			(stroke
				(width 0.1524)
				(type default)
			)
			(layer "F.SilkS")
		)
		(fp_line
			(start 1.2954 -0.5842)
			(end 1.2954 0.5842)
			(stroke
				(width 0.1524)
				(type default)
			)
			(layer "F.SilkS")
		)
		(fp_line
			(start -0.8636 0.4572)
			(end -0.8636 0.4064)
			(stroke
				(width 0.1)
				(type default)
			)
			(layer "F.Fab")
		)
		(fp_line
			(start 0.8636 0.4572)
			(end -0.8636 0.4572)
			(stroke
				(width 0.1)
				(type default)
			)
			(layer "F.Fab")
		)
		(fp_line
			(start -1.1938 0.4064)
			(end -1.1938 -0.4064)
			(stroke
				(width 0.1)
				(type default)
			)
			(layer "F.Fab")
		)
		(fp_line
			(start -0.8636 0.4064)
			(end -1.1938 0.4064)
			(stroke
				(width 0.1)
				(type default)
			)
			(layer "F.Fab")
		)
		(fp_line
			(start 0.8636 0.4064)
			(end 0.8636 0.4572)
			(stroke
				(width 0.1)
				(type default)
			)
			(layer "F.Fab")
		)
		(fp_line
			(start 1.1938 0.4064)
			(end 0.8636 0.4064)
			(stroke
				(width 0.1)
				(type default)
			)
			(layer "F.Fab")
		)
		(fp_line
			(start -1.1938 -0.4064)
			(end -0.8636 -0.4064)
			(stroke
				(width 0.1)
				(type default)
			)
			(layer "F.Fab")
		)
		(fp_line
			(start -0.8636 -0.4064)
			(end -0.8636 -0.4572)
			(stroke
				(width 0.1)
				(type default)
			)
			(layer "F.Fab")
		)
		(fp_line
			(start 0.8636 -0.4064)
			(end 1.1938 -0.4064)
			(stroke
				(width 0.1)
				(type default)
			)
			(layer "F.Fab")
		)
		(fp_line
			(start 1.1938 -0.4064)
			(end 1.1938 0.4064)
			(stroke
				(width 0.1)
				(type default)
			)
			(layer "F.Fab")
		)
		(fp_line
			(start -0.8636 -0.4572)
			(end 0.8636 -0.4572)
			(stroke
				(width 0.1)
				(type default)
			)
			(layer "F.Fab")
		)
		(fp_line
			(start 0.8636 -0.4572)
			(end 0.8636 -0.4064)
			(stroke
				(width 0.1)
				(type default)
			)
			(layer "F.Fab")
		)
		(pad "1" smd rect
			(at -0.7366 0 180)
			(size 0.7112 0.8128)
			(layers "F.Cu" "F.Mask" "F.Paste")
			(net "P0V8_PEX0")
		)
		(pad "2" smd rect
			(at 0.7366 0 180)
			(size 0.7112 0.8128)
			(layers "F.Cu" "F.Mask" "F.Paste")
			(net "GND")
		)
	)
	(footprint ""
		(layer "F.Cu")
		(at 33.11144 -261.434834)
		(property "Reference" "L91"
			(at 0 0 0)
			(layer "F.SilkS")
			(hide yes)
			(effects
				(font
					(size 1.27 1.27)
				)
			)
		)
		(property "Value" ""
			(at 0 0 0)
			(layer "F.Fab")
			(effects
				(font
					(size 1.27 1.27)
				)
			)
		)
		(duplicate_pad_numbers_are_jumpers no)
		(fp_line
			(start -1.63576 -0.8128)
			(end -1.63576 0.8128)
			(stroke
				(width 0.1524)
				(type default)
			)
			(layer "F.SilkS")
		)
		(fp_line
			(start -1.63576 -0.8128)
			(end 1.63576 -0.8128)
			(stroke
				(width 0.1524)
				(type default)
			)
			(layer "F.SilkS")
		)
		(fp_line
			(start 1.63576 -0.8128)
			(end 1.63576 0.8128)
			(stroke
				(width 0.1524)
				(type default)
			)
			(layer "F.SilkS")
		)
		(fp_line
			(start 1.63576 0.8128)
			(end -1.63576 0.8128)
			(stroke
				(width 0.1524)
				(type default)
			)
			(layer "F.SilkS")
		)
		(fp_line
			(start -1.56083 -0.738632)
			(end -1.56083 0.7366)
			(stroke
				(width 0.1)
				(type default)
			)
			(layer "F.Fab")
		)
		(fp_line
			(start -1.56083 0.7366)
			(end -1.524 0.7366)
			(stroke
				(width 0.1)
				(type default)
			)
			(layer "F.Fab")
		)
		(fp_line
			(start -1.524 0.7366)
			(end 1.524 0.7366)
			(stroke
				(width 0.1)
				(type default)
			)
			(layer "F.Fab")
		)
		(fp_line
			(start 1.524 0.7366)
			(end 1.560576 0.7366)
			(stroke
				(width 0.1)
				(type default)
			)
			(layer "F.Fab")
		)
		(fp_line
			(start 1.560576 -0.738632)
			(end -1.56083 -0.738632)
			(stroke
				(width 0.1)
				(type default)
			)
			(layer "F.Fab")
		)
		(fp_line
			(start 1.560576 0.7366)
			(end 1.560576 -0.738632)
			(stroke
				(width 0.1)
				(type default)
			)
			(layer "F.Fab")
		)
		(pad "1" smd rect
			(at -0.94996 0 180)
			(size 1.1176 1.3716)
			(layers "F.Cu" "F.Mask" "F.Paste")
			(net "P1V8_PLL0_PEX0")
		)
		(pad "2" smd rect
			(at 0.94996 0 180)
			(size 1.1176 1.3716)
			(layers "F.Cu" "F.Mask" "F.Paste")
			(net "PCEPLL3_VDDA18_PEX0")
		)
	)
	(footprint ""
		(layer "F.Cu")
		(at 145.749772 -320.900044)
		(property "Reference" "H92"
			(at -6.472174 -7.392416 0)
			(unlocked yes)
			(layer "F.SilkS")
			(effects
				(font
					(size 0.7874 0.5842)
					(thickness 0.1524)
				)
				(justify left)
			)
		)
		(property "Value" ""
			(at 0 0 0)
			(layer "F.Fab")
			(effects
				(font
					(size 1.27 1.27)
				)
			)
		)
		(duplicate_pad_numbers_are_jumpers no)
		(fp_arc
			(start 5.324856 5.97027)
			(mid -7.300568 -3.271407)
			(end 7.999984 0)
			(stroke
				(width 0.1524)
				(type default)
			)
			(layer "F.SilkS")
		)
		(fp_arc
			(start 5.515356 5.794756)
			(mid -7.352116 -3.152493)
			(end 7.999984 0)
			(stroke
				(width 0.1524)
				(type default)
			)
			(layer "B.SilkS")
		)
		(fp_arc
			(start 7.999984 0)
			(mid 7.993661 0.319405)
			(end 7.974584 0.638302)
			(stroke
				(width 0.1524)
				(type default)
			)
			(layer "B.SilkS")
		)
		(fp_circle
			(center 0 0)
			(end 7.999984 0)
			(stroke
				(width 0.1)
				(type default)
			)
			(fill no)
			(layer "B.Fab")
		)
		(fp_circle
			(center 0 0)
			(end 7.999984 0)
			(stroke
				(width 0.1)
				(type default)
			)
			(fill no)
			(layer "F.Fab")
		)
		(pad "" np_thru_hole circle
			(at 0 0)
			(size 4.5212 4.5212)
			(drill 4.5212)
			(layers "*.Cu" "*.Mask")
			(clearance 0.381)
			(thermal_gap 0.381)
		)
		(pad "2" thru_hole circle
			(at 3.6322 0)
			(size 0.762 0.762)
			(drill 0.5588)
			(layers "*.Cu" "*.Mask")
			(remove_unused_layers no)
			(net "GND")
			(clearance 0.1524)
			(thermal_gap 0.1524)
		)
		(pad "3" thru_hole circle
			(at 2.568448 -2.568448)
			(size 0.762 0.762)
			(drill 0.5588)
			(layers "*.Cu" "*.Mask")
			(remove_unused_layers no)
			(net "GND")
			(clearance 0.1524)
			(thermal_gap 0.1524)
		)
		(pad "4" thru_hole circle
			(at 0 -3.6322)
			(size 0.762 0.762)
			(drill 0.5588)
			(layers "*.Cu" "*.Mask")
			(remove_unused_layers no)
			(net "GND")
			(clearance 0.1524)
			(thermal_gap 0.1524)
		)
		(pad "5" thru_hole circle
			(at -2.568448 -2.568448)
			(size 0.762 0.762)
			(drill 0.5588)
			(layers "*.Cu" "*.Mask")
			(remove_unused_layers no)
			(net "GND")
			(clearance 0.1524)
			(thermal_gap 0.1524)
		)
		(pad "6" thru_hole circle
			(at -3.6322 0)
			(size 0.762 0.762)
			(drill 0.5588)
			(layers "*.Cu" "*.Mask")
			(remove_unused_layers no)
			(net "GND")
			(clearance 0.1524)
			(thermal_gap 0.1524)
		)
		(pad "7" thru_hole circle
			(at -2.568448 2.568448)
			(size 0.762 0.762)
			(drill 0.5588)
			(layers "*.Cu" "*.Mask")
			(remove_unused_layers no)
			(net "GND")
			(clearance 0.1524)
			(thermal_gap 0.1524)
		)
		(pad "8" thru_hole circle
			(at 0 3.6322)
			(size 0.762 0.762)
			(drill 0.5588)
			(layers "*.Cu" "*.Mask")
			(remove_unused_layers no)
			(net "GND")
			(clearance 0.1524)
			(thermal_gap 0.1524)
		)
		(pad "9" thru_hole circle
			(at 2.568448 2.568448)
			(size 0.762 0.762)
			(drill 0.5588)
			(layers "*.Cu" "*.Mask")
			(remove_unused_layers no)
			(net "GND")
			(clearance 0.1524)
			(thermal_gap 0.1524)
		)
		(zone
			(layer "F.Cu")
			(hatch none 0.5)
			(connect_pads
				(clearance 0)
			)
			(min_thickness 0.25)
			(keepout
				(tracks not_allowed)
				(vias allowed)
				(pads allowed)
				(copperpour not_allowed)
				(footprints allowed)
			)
			(placement
				(enabled no)
				(sheetname "")
			)
			(fill
				(thermal_gap 0.5)
				(thermal_bridge_width 0.5)
				(island_removal_mode 0)
			)
			(polygon
				(pts
					(arc
						(start 145.749772 -312.90006)
						(mid 137.749788 -320.900044)
						(end 145.749772 -328.900028)
					)
					(arc
						(start 145.749772 -325.649844)
						(mid 140.999972 -320.900044)
						(end 145.749772 -316.150244)
					)
				)
			)
		)
		(zone
			(layer "F.Cu")
			(hatch none 0.5)
			(connect_pads
				(clearance 0)
			)
			(min_thickness 0.25)
			(keepout
				(tracks not_allowed)
				(vias allowed)
				(pads allowed)
				(copperpour not_allowed)
				(footprints allowed)
			)
			(placement
				(enabled no)
				(sheetname "")
			)
			(fill
				(thermal_gap 0.5)
				(thermal_bridge_width 0.5)
				(island_removal_mode 0)
			)
			(polygon
				(pts
					(arc
						(start 145.749772 -312.90006)
						(mid 153.749756 -320.900044)
						(end 145.749772 -328.900028)
					)
					(arc
						(start 145.749772 -325.649844)
						(mid 150.499572 -320.900044)
						(end 145.749772 -316.150244)
					)
				)
			)
		)
		(zone
			(layers "F.Cu" "B.Cu" "In1.Cu" "In2.Cu" "In3.Cu" "In4.Cu" "In5.Cu" "In6.Cu"
				"In7.Cu" "In8.Cu" "In9.Cu" "In10.Cu" "In11.Cu" "In12.Cu" "In13.Cu" "In14.Cu"
				"In15.Cu" "In16.Cu"
			)
			(hatch none 0.5)
			(connect_pads
				(clearance 0)
			)
			(min_thickness 0.25)
			(keepout
				(tracks not_allowed)
				(vias allowed)
				(pads allowed)
				(copperpour not_allowed)
				(footprints allowed)
			)
			(placement
				(enabled no)
				(sheetname "")
			)
			(fill
				(thermal_gap 0.5)
				(thermal_bridge_width 0.5)
				(island_removal_mode 0)
			)
			(polygon
				(pts
					(arc
						(start 148.515832 -320.900044)
						(mid 142.983712 -320.900044)
						(end 148.515832 -320.900044)
					)
				)
			)
		)
		(zone
			(layer "B.Cu")
			(hatch none 0.5)
			(connect_pads
				(clearance 0)
			)
			(min_thickness 0.25)
			(keepout
				(tracks not_allowed)
				(vias allowed)
				(pads allowed)
				(copperpour not_allowed)
				(footprints allowed)
			)
			(placement
				(enabled no)
				(sheetname "")
			)
			(fill
				(thermal_gap 0.5)
				(thermal_bridge_width 0.5)
				(island_removal_mode 0)
			)
			(polygon
				(pts
					(arc
						(start 145.749772 -315.896244)
						(mid 140.745972 -320.900044)
						(end 145.749772 -325.903844)
					)
					(arc
						(start 145.749772 -325.421244)
						(mid 141.228572 -320.900044)
						(end 145.749772 -316.378844)
					)
				)
			)
		)
		(zone
			(layer "B.Cu")
			(hatch none 0.5)
			(connect_pads
				(clearance 0)
			)
			(min_thickness 0.25)
			(keepout
				(tracks not_allowed)
				(vias allowed)
				(pads allowed)
				(copperpour not_allowed)
				(footprints allowed)
			)
			(placement
				(enabled no)
				(sheetname "")
			)
			(fill
				(thermal_gap 0.5)
				(thermal_bridge_width 0.5)
				(island_removal_mode 0)
			)
			(polygon
				(pts
					(arc
						(start 145.749772 -315.896244)
						(mid 150.753572 -320.900044)
						(end 145.749772 -325.903844)
					)
					(arc
						(start 145.749772 -325.421244)
						(mid 150.270972 -320.900044)
						(end 145.749772 -316.378844)
					)
				)
			)
		)
	)
	(footprint ""
		(layer "F.Cu")
		(at 347.842586 -258.14655 180)
		(property "Reference" "PR143"
			(at 0 0 180)
			(layer "F.SilkS")
			(hide yes)
			(effects
				(font
					(size 1.27 1.27)
				)
			)
		)
		(property "Value" ""
			(at 0 0 180)
			(layer "F.Fab")
			(effects
				(font
					(size 1.27 1.27)
				)
			)
		)
		(duplicate_pad_numbers_are_jumpers no)
		(fp_line
			(start 0.7874 0.4064)
			(end -0.7874 0.4064)
			(stroke
				(width 0.1524)
				(type default)
			)
			(layer "F.SilkS")
		)
		(fp_line
			(start 0.7874 -0.4064)
			(end 0.7874 0.4064)
			(stroke
				(width 0.1524)
				(type default)
			)
			(layer "F.SilkS")
		)
		(fp_line
			(start -0.7874 0.4064)
			(end -0.7874 -0.4064)
			(stroke
				(width 0.1524)
				(type default)
			)
			(layer "F.SilkS")
		)
		(fp_line
			(start -0.7874 -0.4064)
			(end 0.7874 -0.4064)
			(stroke
				(width 0.1524)
				(type default)
			)
			(layer "F.SilkS")
		)
		(fp_line
			(start 0.67945 0.3048)
			(end 0.120396 0.3048)
			(stroke
				(width 0.1)
				(type default)
			)
			(layer "F.Fab")
		)
		(fp_line
			(start 0.67945 -0.3048)
			(end 0.67945 0.3048)
			(stroke
				(width 0.1)
				(type default)
			)
			(layer "F.Fab")
		)
		(fp_line
			(start 0.12065 -0.2794)
			(end 0.12065 -0.3048)
			(stroke
				(width 0.1)
				(type default)
			)
			(layer "F.Fab")
		)
		(fp_line
			(start 0.12065 -0.3048)
			(end 0.67945 -0.3048)
			(stroke
				(width 0.1)
				(type default)
			)
			(layer "F.Fab")
		)
		(fp_line
			(start 0.120396 0.3048)
			(end 0.120396 0.2794)
			(stroke
				(width 0.1)
				(type default)
			)
			(layer "F.Fab")
		)
		(fp_line
			(start 0.120396 0.2794)
			(end -0.12065 0.2794)
			(stroke
				(width 0.1)
				(type default)
			)
			(layer "F.Fab")
		)
		(fp_line
			(start -0.12065 0.3048)
			(end -0.67945 0.3048)
			(stroke
				(width 0.1)
				(type default)
			)
			(layer "F.Fab")
		)
		(fp_line
			(start -0.12065 0.2794)
			(end -0.12065 0.3048)
			(stroke
				(width 0.1)
				(type default)
			)
			(layer "F.Fab")
		)
		(fp_line
			(start -0.12065 -0.2794)
			(end 0.12065 -0.2794)
			(stroke
				(width 0.1)
				(type default)
			)
			(layer "F.Fab")
		)
		(fp_line
			(start -0.12065 -0.305054)
			(end -0.12065 -0.2794)
			(stroke
				(width 0.1)
				(type default)
			)
			(layer "F.Fab")
		)
		(fp_line
			(start -0.67945 0.3048)
			(end -0.67945 -0.305054)
			(stroke
				(width 0.1)
				(type default)
			)
			(layer "F.Fab")
		)
		(fp_line
			(start -0.67945 -0.305054)
			(end -0.12065 -0.305054)
			(stroke
				(width 0.1)
				(type default)
			)
			(layer "F.Fab")
		)
		(pad "1" smd circle
			(at -0.40005 0 180)
			(size 0 0)
			(layers "F.Cu" "F.Mask" "F.Paste")
			(net "P0V8_PEX2_IINSEN")
		)
		(pad "2" smd circle
			(at 0.40005 0 180)
			(size 0 0)
			(layers "F.Cu" "F.Mask" "F.Paste")
			(net "GND")
		)
	)
)
